# T6G (Grand Teton) — schematic netlist excerpt (pin names and nets, part order shuffled) for the footprints in the layout excerpt that follows; sources: Cadence DE-HDL packaged netlist, KiCad conversion of 04192023_DAF0TMB3IC0_F0TG_MB_C_brd_V02_OCP.brd

R6183  Q_RES  0 5% CHIP  pkg 0402LF  page 82 : A = FM_SEC_MUX_OE_N ; B = FM_SEC_MUX_OE_R_N
R1168  Q_RES  0 5% CHIP  pkg 0402LF  page 142 : A = P12V_OCP_V3_2_BUF_EN ; B = P12V_OCP_V3_2_BUF_EN_R

(kicad_pcb
	(version 20260206)
	(generator "pcbnew")
	(generator_version "10.0")
	(general
		(thickness 1.6)
		(legacy_teardrops no)
	)
	(paper "A4")
	(title_block
		(title "04192023_DAF0TMB3IC0_F0TG_MB_C_brd_V02_OCP.brd")
		(comment 1 "Grand Teton / footprints 4902-4903 of 8354")
	)
	(layers
		(0 "F.Cu" signal "TOP")
		(4 "In1.Cu" signal "GND")
		(6 "In2.Cu" signal "IN1")
		(8 "In3.Cu" signal "GND1")
		(10 "In4.Cu" signal "IN2")
		(12 "In5.Cu" signal "GND2")
		(14 "In6.Cu" signal "IN3")
		(16 "In7.Cu" signal "GND3")
		(18 "In8.Cu" signal "VCC")
		(20 "In9.Cu" signal "VCC1")
		(22 "In10.Cu" signal "GND4")
		(24 "In11.Cu" signal "IN4")
		(26 "In12.Cu" signal "GND5")
		(28 "In13.Cu" signal "IN5")
		(30 "In14.Cu" signal "GND6")
		(32 "In15.Cu" signal "IN6")
		(34 "In16.Cu" signal "GND7")
		(2 "B.Cu" signal "BOTTOM")
		(9 "F.Adhes" user "F.Adhesive")
		(11 "B.Adhes" user "B.Adhesive")
		(13 "F.Paste" user "Package Geometry/Pastemask Top")
		(15 "B.Paste" user "Package Geometry/Pastemask Bottom")
		(5 "F.SilkS" user "Ref Des/Silkscreen Top")
		(7 "B.SilkS" user "Ref Des/Silkscreen Bottom")
		(1 "F.Mask" user "Board Geometry/Soldermask Top")
		(3 "B.Mask" user "Board Geometry/Soldermask Bottom")
		(17 "Dwgs.User" user "User.Drawings")
		(19 "Cmts.User" user "User.Comments")
		(21 "Eco1.User" user "User.Eco1")
		(23 "Eco2.User" user "User.Eco2")
		(25 "Edge.Cuts" user "Board Geometry/Outline")
		(27 "Margin" user)
		(31 "F.CrtYd" user "Package Geometry/Place Bound Top")
		(29 "B.CrtYd" user "Package Geometry/Place Bound Bottom")
		(35 "F.Fab" user "Ref Des/Assembly Top")
		(33 "B.Fab" user "Ref Des/Assembly Bottom")
	)
	(footprint ""
		(layer "F.Cu")
		(at 171.20743 -102.993952)
		(property "Reference" "R6183"
			(at 0 0 0)
			(layer "F.SilkS")
			(hide yes)
			(effects
				(font
					(size 1.27 1.27)
				)
			)
		)
		(property "Value" ""
			(at 0 0 0)
			(layer "F.Fab")
			(effects
				(font
					(size 1.27 1.27)
				)
			)
		)
		(duplicate_pad_numbers_are_jumpers no)
		(fp_line
			(start -0.7874 -0.4064)
			(end 0.7874 -0.4064)
			(stroke
				(width 0.1524)
				(type default)
			)
			(layer "F.SilkS")
		)
		(fp_line
			(start -0.7874 0.4064)
			(end -0.7874 -0.4064)
			(stroke
				(width 0.1524)
				(type default)
			)
			(layer "F.SilkS")
		)
		(fp_line
			(start 0.7874 -0.4064)
			(end 0.7874 0.4064)
			(stroke
				(width 0.1524)
				(type default)
			)
			(layer "F.SilkS")
		)
		(fp_line
			(start 0.7874 0.4064)
			(end -0.7874 0.4064)
			(stroke
				(width 0.1524)
				(type default)
			)
			(layer "F.SilkS")
		)
		(fp_line
			(start -0.67945 -0.305054)
			(end -0.12065 -0.305054)
			(stroke
				(width 0.1)
				(type default)
			)
			(layer "F.Fab")
		)
		(fp_line
			(start -0.67945 0.3048)
			(end -0.67945 -0.305054)
			(stroke
				(width 0.1)
				(type default)
			)
			(layer "F.Fab")
		)
		(fp_line
			(start -0.12065 -0.305054)
			(end -0.12065 -0.2794)
			(stroke
				(width 0.1)
				(type default)
			)
			(layer "F.Fab")
		)
		(fp_line
			(start -0.12065 -0.2794)
			(end 0.12065 -0.2794)
			(stroke
				(width 0.1)
				(type default)
			)
			(layer "F.Fab")
		)
		(fp_line
			(start -0.12065 0.2794)
			(end -0.12065 0.3048)
			(stroke
				(width 0.1)
				(type default)
			)
			(layer "F.Fab")
		)
		(fp_line
			(start -0.12065 0.3048)
			(end -0.67945 0.3048)
			(stroke
				(width 0.1)
				(type default)
			)
			(layer "F.Fab")
		)
		(fp_line
			(start 0.120396 0.2794)
			(end -0.12065 0.2794)
			(stroke
				(width 0.1)
				(type default)
			)
			(layer "F.Fab")
		)
		(fp_line
			(start 0.120396 0.3048)
			(end 0.120396 0.2794)
			(stroke
				(width 0.1)
				(type default)
			)
			(layer "F.Fab")
		)
		(fp_line
			(start 0.12065 -0.3048)
			(end 0.67945 -0.3048)
			(stroke
				(width 0.1)
				(type default)
			)
			(layer "F.Fab")
		)
		(fp_line
			(start 0.12065 -0.2794)
			(end 0.12065 -0.3048)
			(stroke
				(width 0.1)
				(type default)
			)
			(layer "F.Fab")
		)
		(fp_line
			(start 0.67945 -0.3048)
			(end 0.67945 0.3048)
			(stroke
				(width 0.1)
				(type default)
			)
			(layer "F.Fab")
		)
		(fp_line
			(start 0.67945 0.3048)
			(end 0.120396 0.3048)
			(stroke
				(width 0.1)
				(type default)
			)
			(layer "F.Fab")
		)
		(pad "1" smd circle
			(at -0.40005 0)
			(size 0 0)
			(layers "F.Cu" "F.Mask" "F.Paste")
			(net "FM_SEC_MUX_OE_N")
		)
		(pad "2" smd circle
			(at 0.40005 0)
			(size 0 0)
			(layers "F.Cu" "F.Mask" "F.Paste")
			(net "FM_SEC_MUX_OE_R_N")
		)
	)
	(footprint ""
		(layer "F.Cu")
		(at 56.858408 -37.7825)
		(property "Reference" "R1168"
			(at 0 0 0)
			(layer "F.SilkS")
			(hide yes)
			(effects
				(font
					(size 1.27 1.27)
				)
			)
		)
		(property "Value" ""
			(at 0 0 0)
			(layer "F.Fab")
			(effects
				(font
					(size 1.27 1.27)
				)
			)
		)
		(duplicate_pad_numbers_are_jumpers no)
		(fp_line
			(start -0.7874 -0.4064)
			(end 0.7874 -0.4064)
			(stroke
				(width 0.1524)
				(type default)
			)
			(layer "F.SilkS")
		)
		(fp_line
			(start -0.7874 0.4064)
			(end -0.7874 -0.4064)
			(stroke
				(width 0.1524)
				(type default)
			)
			(layer "F.SilkS")
		)
		(fp_line
			(start 0.7874 -0.4064)
			(end 0.7874 0.4064)
			(stroke
				(width 0.1524)
				(type default)
			)
			(layer "F.SilkS")
		)
		(fp_line
			(start 0.7874 0.4064)
			(end -0.7874 0.4064)
			(stroke
				(width 0.1524)
				(type default)
			)
			(layer "F.SilkS")
		)
		(fp_line
			(start -0.67945 -0.305054)
			(end -0.12065 -0.305054)
			(stroke
				(width 0.1)
				(type default)
			)
			(layer "F.Fab")
		)
		(fp_line
			(start -0.67945 0.3048)
			(end -0.67945 -0.305054)
			(stroke
				(width 0.1)
				(type default)
			)
			(layer "F.Fab")
		)
		(fp_line
			(start -0.12065 -0.305054)
			(end -0.12065 -0.2794)
			(stroke
				(width 0.1)
				(type default)
			)
			(layer "F.Fab")
		)
		(fp_line
			(start -0.12065 -0.2794)
			(end 0.12065 -0.2794)
			(stroke
				(width 0.1)
				(type default)
			)
			(layer "F.Fab")
		)
		(fp_line
			(start -0.12065 0.2794)
			(end -0.12065 0.3048)
			(stroke
				(width 0.1)
				(type default)
			)
			(layer "F.Fab")
		)
		(fp_line
			(start -0.12065 0.3048)
			(end -0.67945 0.3048)
			(stroke
				(width 0.1)
				(type default)
			)
			(layer "F.Fab")
		)
		(fp_line
			(start 0.120396 0.2794)
			(end -0.12065 0.2794)
			(stroke
				(width 0.1)
				(type default)
			)
			(layer "F.Fab")
		)
		(fp_line
			(start 0.120396 0.3048)
			(end 0.120396 0.2794)
			(stroke
				(width 0.1)
				(type default)
			)
			(layer "F.Fab")
		)
		(fp_line
			(start 0.12065 -0.3048)
			(end 0.67945 -0.3048)
			(stroke
				(width 0.1)
				(type default)
			)
			(layer "F.Fab")
		)
		(fp_line
			(start 0.12065 -0.2794)
			(end 0.12065 -0.3048)
			(stroke
				(width 0.1)
				(type default)
			)
			(layer "F.Fab")
		)
		(fp_line
			(start 0.67945 -0.3048)
			(end 0.67945 0.3048)
			(stroke
				(width 0.1)
				(type default)
			)
			(layer "F.Fab")
		)
		(fp_line
			(start 0.67945 0.3048)
			(end 0.120396 0.3048)
			(stroke
				(width 0.1)
				(type default)
			)
			(layer "F.Fab")
		)
		(pad "1" smd circle
			(at -0.40005 0)
			(size 0 0)
			(layers "F.Cu" "F.Mask" "F.Paste")
			(net "P12V_OCP_V3_2_BUF_EN")
		)
		(pad "2" smd circle
			(at 0.40005 0)
			(size 0 0)
			(layers "F.Cu" "F.Mask" "F.Paste")
			(net "P12V_OCP_V3_2_BUF_EN_R")
		)
	)
)
